# T6G (Grand Teton) — schematic netlist excerpt (pin names and nets, part order shuffled) for the footprints in the layout excerpt that follows; sources: Cadence DE-HDL packaged netlist, KiCad conversion of 04192023_DAF0TMB3IC0_F0TG_MB_C_brd_V02_OCP.brd

R143  Q_RES  0 5% EMPTY  pkg 0402LF  page 161 : A = SMB_CPU0_CPU1_APML_MUX1_SDA ; B = SMB_APML_CPU0_R_SDA
R1501  Q_RES  10K 5% EMPTY  pkg 0402LF  page 76 : A = PVDD18_S5_P1 ; B = CLK_CPU1_RTCCLK

(kicad_pcb
	(version 20260206)
	(generator "pcbnew")
	(generator_version "10.0")
	(general
		(thickness 1.6)
		(legacy_teardrops no)
	)
	(paper "A4")
	(title_block
		(title "04192023_DAF0TMB3IC0_F0TG_MB_C_brd_V02_OCP.brd")
		(comment 1 "Grand Teton / footprints 5776-5777 of 8354")
	)
	(layers
		(0 "F.Cu" signal "TOP")
		(4 "In1.Cu" signal "GND")
		(6 "In2.Cu" signal "IN1")
		(8 "In3.Cu" signal "GND1")
		(10 "In4.Cu" signal "IN2")
		(12 "In5.Cu" signal "GND2")
		(14 "In6.Cu" signal "IN3")
		(16 "In7.Cu" signal "GND3")
		(18 "In8.Cu" signal "VCC")
		(20 "In9.Cu" signal "VCC1")
		(22 "In10.Cu" signal "GND4")
		(24 "In11.Cu" signal "IN4")
		(26 "In12.Cu" signal "GND5")
		(28 "In13.Cu" signal "IN5")
		(30 "In14.Cu" signal "GND6")
		(32 "In15.Cu" signal "IN6")
		(34 "In16.Cu" signal "GND7")
		(2 "B.Cu" signal "BOTTOM")
		(9 "F.Adhes" user "F.Adhesive")
		(11 "B.Adhes" user "B.Adhesive")
		(13 "F.Paste" user "Package Geometry/Pastemask Top")
		(15 "B.Paste" user "Package Geometry/Pastemask Bottom")
		(5 "F.SilkS" user "Ref Des/Silkscreen Top")
		(7 "B.SilkS" user "Ref Des/Silkscreen Bottom")
		(1 "F.Mask" user "Board Geometry/Soldermask Top")
		(3 "B.Mask" user "Board Geometry/Soldermask Bottom")
		(17 "Dwgs.User" user "User.Drawings")
		(19 "Cmts.User" user "User.Comments")
		(21 "Eco1.User" user "User.Eco1")
		(23 "Eco2.User" user "User.Eco2")
		(25 "Edge.Cuts" user "Board Geometry/Outline")
		(27 "Margin" user)
		(31 "F.CrtYd" user "Package Geometry/Place Bound Top")
		(29 "B.CrtYd" user "Package Geometry/Place Bound Bottom")
		(35 "F.Fab" user "Ref Des/Assembly Top")
		(33 "B.Fab" user "Ref Des/Assembly Bottom")
	)
	(footprint ""
		(layer "B.Cu")
		(at 145.124678 -318.208152 180)
		(property "Reference" "R1501"
			(at 0 0 0)
			(layer "B.SilkS")
			(hide yes)
			(effects
				(font
					(size 1.27 1.27)
				)
				(justify mirror)
			)
		)
		(property "Value" ""
			(at 0 0 0)
			(layer "B.Fab")
			(effects
				(font
					(size 1.27 1.27)
				)
				(justify mirror)
			)
		)
		(duplicate_pad_numbers_are_jumpers no)
		(fp_line
			(start 0.7874 0.4064)
			(end 0.7874 -0.4064)
			(stroke
				(width 0.1524)
				(type default)
			)
			(layer "B.SilkS")
		)
		(fp_line
			(start 0.7874 -0.4064)
			(end -0.7874 -0.4064)
			(stroke
				(width 0.1524)
				(type default)
			)
			(layer "B.SilkS")
		)
		(fp_line
			(start -0.7874 0.4064)
			(end 0.7874 0.4064)
			(stroke
				(width 0.1524)
				(type default)
			)
			(layer "B.SilkS")
		)
		(fp_line
			(start -0.7874 -0.4064)
			(end -0.7874 0.4064)
			(stroke
				(width 0.1524)
				(type default)
			)
			(layer "B.SilkS")
		)
		(fp_line
			(start 0.67945 0.3048)
			(end 0.67945 -0.305054)
			(stroke
				(width 0.1)
				(type default)
			)
			(layer "B.Fab")
		)
		(fp_line
			(start 0.67945 -0.305054)
			(end 0.12065 -0.305054)
			(stroke
				(width 0.1)
				(type default)
			)
			(layer "B.Fab")
		)
		(fp_line
			(start 0.12065 0.3048)
			(end 0.67945 0.3048)
			(stroke
				(width 0.1)
				(type default)
			)
			(layer "B.Fab")
		)
		(fp_line
			(start 0.12065 0.2794)
			(end 0.12065 0.3048)
			(stroke
				(width 0.1)
				(type default)
			)
			(layer "B.Fab")
		)
		(fp_line
			(start 0.12065 -0.2794)
			(end -0.12065 -0.2794)
			(stroke
				(width 0.1)
				(type default)
			)
			(layer "B.Fab")
		)
		(fp_line
			(start 0.12065 -0.305054)
			(end 0.12065 -0.2794)
			(stroke
				(width 0.1)
				(type default)
			)
			(layer "B.Fab")
		)
		(fp_line
			(start -0.120396 0.3048)
			(end -0.120396 0.2794)
			(stroke
				(width 0.1)
				(type default)
			)
			(layer "B.Fab")
		)
		(fp_line
			(start -0.120396 0.2794)
			(end 0.12065 0.2794)
			(stroke
				(width 0.1)
				(type default)
			)
			(layer "B.Fab")
		)
		(fp_line
			(start -0.12065 -0.2794)
			(end -0.12065 -0.3048)
			(stroke
				(width 0.1)
				(type default)
			)
			(layer "B.Fab")
		)
		(fp_line
			(start -0.12065 -0.3048)
			(end -0.67945 -0.3048)
			(stroke
				(width 0.1)
				(type default)
			)
			(layer "B.Fab")
		)
		(fp_line
			(start -0.67945 0.3048)
			(end -0.120396 0.3048)
			(stroke
				(width 0.1)
				(type default)
			)
			(layer "B.Fab")
		)
		(fp_line
			(start -0.67945 -0.3048)
			(end -0.67945 0.3048)
			(stroke
				(width 0.1)
				(type default)
			)
			(layer "B.Fab")
		)
		(pad "1" smd circle
			(at 0.40005 0)
			(size 0 0)
			(layers "B.Cu" "B.Mask" "B.Paste")
			(net "PVDD18_S5_P1")
		)
		(pad "2" smd circle
			(at -0.40005 0)
			(size 0 0)
			(layers "B.Cu" "B.Mask" "B.Paste")
			(net "CLK_CPU1_RTCCLK")
		)
	)
	(footprint ""
		(layer "B.Cu")
		(at 229.997 -240.03)
		(property "Reference" "R143"
			(at 0 0 0)
			(layer "B.SilkS")
			(hide yes)
			(effects
				(font
					(size 1.27 1.27)
				)
				(justify mirror)
			)
		)
		(property "Value" ""
			(at 0 0 0)
			(layer "B.Fab")
			(effects
				(font
					(size 1.27 1.27)
				)
				(justify mirror)
			)
		)
		(duplicate_pad_numbers_are_jumpers no)
		(fp_line
			(start -0.7874 -0.4064)
			(end -0.7874 0.4064)
			(stroke
				(width 0.1524)
				(type default)
			)
			(layer "B.SilkS")
		)
		(fp_line
			(start -0.7874 0.4064)
			(end 0.7874 0.4064)
			(stroke
				(width 0.1524)
				(type default)
			)
			(layer "B.SilkS")
		)
		(fp_line
			(start 0.7874 -0.4064)
			(end -0.7874 -0.4064)
			(stroke
				(width 0.1524)
				(type default)
			)
			(layer "B.SilkS")
		)
		(fp_line
			(start 0.7874 0.4064)
			(end 0.7874 -0.4064)
			(stroke
				(width 0.1524)
				(type default)
			)
			(layer "B.SilkS")
		)
		(fp_line
			(start -0.67945 -0.3048)
			(end -0.67945 0.3048)
			(stroke
				(width 0.1)
				(type default)
			)
			(layer "B.Fab")
		)
		(fp_line
			(start -0.67945 0.3048)
			(end -0.120396 0.3048)
			(stroke
				(width 0.1)
				(type default)
			)
			(layer "B.Fab")
		)
		(fp_line
			(start -0.12065 -0.3048)
			(end -0.67945 -0.3048)
			(stroke
				(width 0.1)
				(type default)
			)
			(layer "B.Fab")
		)
		(fp_line
			(start -0.12065 -0.2794)
			(end -0.12065 -0.3048)
			(stroke
				(width 0.1)
				(type default)
			)
			(layer "B.Fab")
		)
		(fp_line
			(start -0.120396 0.2794)
			(end 0.12065 0.2794)
			(stroke
				(width 0.1)
				(type default)
			)
			(layer "B.Fab")
		)
		(fp_line
			(start -0.120396 0.3048)
			(end -0.120396 0.2794)
			(stroke
				(width 0.1)
				(type default)
			)
			(layer "B.Fab")
		)
		(fp_line
			(start 0.12065 -0.305054)
			(end 0.12065 -0.2794)
			(stroke
				(width 0.1)
				(type default)
			)
			(layer "B.Fab")
		)
		(fp_line
			(start 0.12065 -0.2794)
			(end -0.12065 -0.2794)
			(stroke
				(width 0.1)
				(type default)
			)
			(layer "B.Fab")
		)
		(fp_line
			(start 0.12065 0.2794)
			(end 0.12065 0.3048)
			(stroke
				(width 0.1)
				(type default)
			)
			(layer "B.Fab")
		)
		(fp_line
			(start 0.12065 0.3048)
			(end 0.67945 0.3048)
			(stroke
				(width 0.1)
				(type default)
			)
			(layer "B.Fab")
		)
		(fp_line
			(start 0.67945 -0.305054)
			(end 0.12065 -0.305054)
			(stroke
				(width 0.1)
				(type default)
			)
			(layer "B.Fab")
		)
		(fp_line
			(start 0.67945 0.3048)
			(end 0.67945 -0.305054)
			(stroke
				(width 0.1)
				(type default)
			)
			(layer "B.Fab")
		)
		(pad "1" smd circle
			(at 0.40005 0 180)
			(size 0 0)
			(layers "B.Cu" "B.Mask" "B.Paste")
			(net "SMB_CPU0_CPU1_APML_MUX1_SDA")
		)
		(pad "2" smd circle
			(at -0.40005 0 180)
			(size 0 0)
			(layers "B.Cu" "B.Mask" "B.Paste")
			(net "SMB_APML_CPU0_R_SDA")
		)
	)
)
